                    - SPARES  LIST -


                    - PART SUMMARY -

24LC16BT_I_ST_TSSOP8-G221-1017A		1
74HCT2G125DP_TSSOP8-G220-00055A		4
74LVC1G07_SC70_5-G220-10017-01		1
AT24MAC402_SOT23_5-A221-00002-A		1
BNO080_LGA_28-A246-00002-FB,BNA		1
CAPACITOR-G104-0A120-FJ,12PF,5%		2
CAPACITOR-G104-0A180-FJ,18PF,5%		9
CAPACITOR-G104-0B101-FK,100PF,A		3
CAPACITOR-G104-0B103-EK,0.01UFA		11
CAPACITOR-G104-0B472-EK,4700PFA		1
CAPACITOR-G104-0F224-BK,0.22UFA		1
CAPACITOR-G105-0A102-FJ,1000PFA		3
CAPACITOR-G105-0B104-CK,0.1UF,A		114
CAPACITOR-G105-0B104-EK,0.1UF,A		77
CAPACITOR-G105-0B222-FK,2200PFA		2
CAPACITOR-G105-0B223-EK,0.022UA		3
CAPACITOR-G105-0B224-DK,0.22UFA		3
CAPACITOR-G105-0C106-BM,10UF,2A		8
CAPACITOR-G105-0F475-BM,4.7UF,A		17
CAPACITOR-G107-0F106-EM,10UF,2A		28
CAPACITOR-G107-0F226-CM,22UF,2A		20
CAPACITOR-G107-0F476-AM,47UF,2A		9
CAPACITOR-G109-0G107-BM,100UF,A		5
CAT93C46VI_GT3_SOIC8-G221-1007A		1
CL1001485A-G122-00019-01		2
CL5003148A-G220-10019-01		1
CONN_64P_GF-S_M_EF64_PCIE_P039A		1
CONN_HDR_1X3_M_S_SMT-G205-1002A		1
CONN_HDR_2X10_M_S_SMT-G200-130A		1
CONN_HDR_2X2_M_S_SMT-G200-1068A		2
CONN_HDR_2X3_M_RA_TH-G200-1251A		1
CONN_HDR_2X4_F_S_SMT-G200-1307A		1
CONN_HDR_2X6_F_S_SMT-G200-1313A		1
CONN_JACK_1P_GH4_S_TH-G200-130A		4
CONN_USB_14P_GH4_F_RA_TH-G200-A		1
CONN_USB_1X5_G2_GH4_F_RA_SMT-GA		1
DIODE_2-G122-00005-01		1
DIODE_2E-G122-10190-01		1
DIODE_2F-G122-10186-01		2
DIODE_3F-G122-10080-01		1
DIODE_4_V1-G122-10123-01		4
FERRITEBEAD-G191-10097-01,600OA		7
FERRITEBEAD-G191-10100-01,120OA		7
FERRITEBEAD-G191-10101-01,26OHA		10
FT4232HL_REEL_QFP64-G223-10282A		1
FUSE-G280-10012-01,2.5A		1
FUSE-G280-10049-01,1A		1
G200_10283_01-G200-10283-01		2
G220_10198_01-G223-10197-01		1
ICP_10100_LGA10-A222-00002-FB,A		1
INDUCTOR_2-G190-10418-01,1.0UHA		1
INDUCTOR_2-G190-10424-01,4.7UHA		2
IS32FL3207_QWLA3_TR_QFN29-A223A		1
ISL80101IRAJZ_DFN10-G222-10136A		4
LED_4P_V14-G170-10189-01		5
LM75BDP_TSSOP8-G220-10215-01		3
MEC_MTH8-MTH125C236N_V8-MTH125A		4
MEC_NPTH-MTH100C240N-MTH100C24A		4
MP5022CGQV_Z_QFN22-G220-10510-A		1
MT25QL128ABA1ESE_SOP8-G221-102A		1
NCP45560IMNTWG_H_DFN12-G222-10A		1
NLASB3157DFT2G_SC88-G223-10187A		2
NULL-G380-10013-01		30
NUT-A200-00029-FB		8
NUT-G340-10437-01		4
OPTICAL-G170-10143-01		14
OSC6P_V2-A130-00003-AW		1
OSC6P_V2-A130-00004-AW		1
PCA9508DP_TSSOP8-G223-10278-01		1
PCA9546APW_TSSOP16-G223-10280-A		1
POWERMOS_3P_NCH_V1-G121-10200-A		2
POWERMOS_3P_PCH-G121-10216-01		1
RESISTOR-A155-05101-DL,5.1KOHMA		2
RESISTOR-G152-00055-01,1.13KOHA		3
RESISTOR-G152-10344-01,30KOHM,A		1
RESISTOR-G155-01202-01,12KOHM,A		1
RESISTOR-G155-01203-01,120KOHMA		1
RESISTOR-G155-02101-01,2.1KOHMA		2
RESISTOR-G155-02262-01,22.6K,1%		1
RESISTOR-G155-02402-01,24KOHM,A		1
RESISTOR-G155-02672-01,26.7K,1%		1
RESISTOR-G155-03001-01,3KOHM,1%		1
RESISTOR-G155-03241-01,3.24KOHA		5
RESISTOR-G155-03322-01,33.2KOHA		1
RESISTOR-G155-03921-01,3.92KOHA		3
RESISTOR-G155-04221-01,4.22KOHA		3
RESISTOR-G155-04421-01,4.42KOHA		1
RESISTOR-G155-05101-01,5.1KOHMA		3
RESISTOR-G155-100R0-J0,0OHM,-		57
RESISTOR-G155-11000-01,100OHM,A		43
RESISTOR-G155-11001-01,1KOHM,1%		33
RESISTOR-G155-11002-01,10KOHM,A		52
RESISTOR-G155-11003-01,100KOHMA		19
RESISTOR-G155-11004-01,1MOHM,1%		6
RESISTOR-G155-11500-01,150OHM,A		4
RESISTOR-G155-11502-01,15KOHM,A		2
RESISTOR-G155-12002-01,20KOHM,A		1
RESISTOR-G155-120R0-01,20OHM,1%		3
RESISTOR-G155-12201-01,2.2KOHMA		3
RESISTOR-G155-13300-01,330OHM,A		16
RESISTOR-G155-133R0-01,33OHM,1%		103
RESISTOR-G155-14701-01,4.7KOHMA		111
RESISTOR-G155-149R9-01,49.9OHMA		8
RESISTOR-G156-049R9-01,49.9OHMA		1
RESISTOR-G156-100R0-J0,0OHM,-		3
RESISTOR-G157-100R0-J0,0OHM,-		1
RESISTOR-G157-12R20-01,2.2OHM,A		3
SHT31A_DIS_B10KS_DFN8-A222-000A		1
SOLDER_PREFORM-G380-10015-01		41
TPS2051BDBVT_SOT23_5-G220-1033A		1
TPS3808G18DBVR_SOT23_6-G222-00A		1
TPS54824RNVR_VQFN18-G220-10657A		3
TP_PIONT-TP010CT020B030_PTH-TPA		92
TS3A5018PWR_TSSOP16-G220-10324A		3
TS3USB3031RMGR_WQFN12-G220-103A		1
XC7A200T_2FBG484C_FBG484-G240-A		1
XTAL_2-G131-10075-01		1
XTAL_4-G131-10038-02		1

Total                                    1119
